# BASEBOARD_FAB2 (Tioga Pass) — schematic netlist excerpt (pin names and nets, part order shuffled) for the footprints in the layout excerpt that follows; sources: Cadence DE-HDL packaged netlist, KiCad conversion of Wiwynn_Tioga_Pass_MB.brd

C7A18  SC1U10V2KX-4-GP  10%  pkg SMD-BCG6  page 219 : \1\ = P5V_STBY ; \2\ = GND
C5G94  CAP_A  22.0UF 4V 20% X6S  pkg 0603V  page 243 : A = PVDDQ_GHJ ; B = GND
L25W1  IND-68NH-15-GP  pkg DISCRET-GC1  page 252 : \1\ = BMC_VGA_BLUE ; \2\ = V_IO_B_J

(kicad_pcb
	(version 20260206)
	(generator "pcbnew")
	(generator_version "10.0")
	(general
		(thickness 1.6)
		(legacy_teardrops no)
	)
	(paper "A4")
	(title_block
		(title "Wiwynn_Tioga_Pass_MB.brd")
		(comment 1 "Tioga Pass / footprints 2497-2499 of 4770")
	)
	(layers
		(0 "F.Cu" signal "TOP")
		(4 "In1.Cu" signal "L2GND")
		(6 "In2.Cu" signal "L3")
		(8 "In3.Cu" signal "L4GND")
		(10 "In4.Cu" signal "L5")
		(12 "In5.Cu" signal "L6GND")
		(14 "In6.Cu" signal "L7VCC")
		(16 "In7.Cu" signal "L8VCC")
		(18 "In8.Cu" signal "L9GND")
		(20 "In9.Cu" signal "L10")
		(22 "In10.Cu" signal "L11GND")
		(24 "In11.Cu" signal "L12")
		(26 "In12.Cu" signal "L13GND")
		(2 "B.Cu" signal "BOTTOM")
		(9 "F.Adhes" user "F.Adhesive")
		(11 "B.Adhes" user "B.Adhesive")
		(13 "F.Paste" user "Package Geometry/Pastemask Top")
		(15 "B.Paste" user "Package Geometry/Pastemask Bottom")
		(5 "F.SilkS" user "Ref Des/Silkscreen Top")
		(7 "B.SilkS" user "Ref Des/Silkscreen Bottom")
		(1 "F.Mask" user "Board Geometry/Soldermask Top")
		(3 "B.Mask" user "Board Geometry/Soldermask Bottom")
		(17 "Dwgs.User" user "User.Drawings")
		(19 "Cmts.User" user "User.Comments")
		(21 "Eco1.User" user "User.Eco1")
		(23 "Eco2.User" user "User.Eco2")
		(25 "Edge.Cuts" user "Board Geometry/Outline")
		(27 "Margin" user)
		(31 "F.CrtYd" user "Package Geometry/Place Bound Top")
		(29 "B.CrtYd" user "Package Geometry/Place Bound Bottom")
		(35 "F.Fab" user "Ref Des/Assembly Top")
		(33 "B.Fab" user "Ref Des/Assembly Bottom")
	)
	(footprint ""
		(layer "B.Cu")
		(at 418.846 -22.225 90)
		(property "Reference" "L25W1"
			(at 0 0 90)
			(layer "B.SilkS")
			(hide yes)
			(effects
				(font
					(size 1.27 1.27)
				)
				(justify mirror)
			)
		)
		(property "Value" "*"
			(at -0.0254 -2.8829 90)
			(unlocked yes)
			(layer "B.Fab")
			(hide yes)
			(effects
				(font
					(size 1.27 1.016)
					(thickness 0.1524)
				)
				(justify mirror)
			)
		)
		(property "Device Type" "IND-68NH-15-GP_DISCRET-GC1-INDA"
			(at -0.0254 -4.4069 90)
			(unlocked yes)
			(layer "B.Fab")
			(hide yes)
			(effects
				(font
					(size 1.27 1.016)
					(thickness 0.1524)
				)
				(justify mirror)
			)
		)
		(duplicate_pad_numbers_are_jumpers no)
		(fp_line
			(start -0.254 0)
			(end 0.254 0)
			(stroke
				(width 0.2032)
				(type default)
			)
			(layer "B.SilkS")
		)
		(fp_rect
			(start 0.5842 1.3335)
			(end -0.5842 -1.3335)
			(stroke
				(width 0)
				(type default)
			)
			(fill no)
			(layer "B.CrtYd")
		)
		(fp_rect
			(start 0.5842 1.3335)
			(end -0.5842 -1.3335)
			(stroke
				(width 0)
				(type default)
			)
			(fill no)
			(layer "B.Fab")
		)
		(pad "1" smd custom
			(at 0 -0.762 270)
			(size 0.2159 0.2159)
			(layers "B.Cu" "B.Mask" "B.Paste")
			(net "BMC_VGA_BLUE")
			(options
				(clearance outline)
				(anchor circle)
			)
			(primitives
				(gr_poly
					(pts
						(arc
							(start -0.3302 0.4318)
							(mid -0.402042 0.402042)
							(end -0.4318 0.3302)
						)
						(arc
							(start -0.4318 -0.3302)
							(mid -0.402042 -0.402042)
							(end -0.3302 -0.4318)
						)
						(arc
							(start 0.3302 -0.4318)
							(mid 0.402042 -0.402042)
							(end 0.4318 -0.3302)
						)
						(arc
							(start 0.4318 0.3302)
							(mid 0.402042 0.402042)
							(end 0.3302 0.4318)
						)
					)
					(width 0)
					(fill yes)
				)
			)
		)
		(pad "2" smd custom
			(at 0 0.762 270)
			(size 0.2159 0.2159)
			(layers "B.Cu" "B.Mask" "B.Paste")
			(net "V_IO_B_J")
			(options
				(clearance outline)
				(anchor circle)
			)
			(primitives
				(gr_poly
					(pts
						(arc
							(start -0.3302 0.4318)
							(mid -0.402042 0.402042)
							(end -0.4318 0.3302)
						)
						(arc
							(start -0.4318 -0.3302)
							(mid -0.402042 -0.402042)
							(end -0.3302 -0.4318)
						)
						(arc
							(start 0.3302 -0.4318)
							(mid 0.402042 -0.402042)
							(end 0.4318 -0.3302)
						)
						(arc
							(start 0.4318 0.3302)
							(mid 0.402042 0.402042)
							(end 0.3302 0.4318)
						)
					)
					(width 0)
					(fill yes)
				)
			)
		)
	)
	(footprint ""
		(layer "B.Cu")
		(at 346.8751 -156.5656 -90)
		(property "Reference" "C7A18"
			(at 0 0 90)
			(layer "B.SilkS")
			(hide yes)
			(effects
				(font
					(size 1.27 1.27)
				)
				(justify mirror)
			)
		)
		(property "Value" "*"
			(at -1.1811 -2.8194 270)
			(unlocked yes)
			(layer "B.Fab")
			(hide yes)
			(effects
				(font
					(size 1.27 1.016)
					(thickness 0.1524)
				)
				(justify mirror)
			)
		)
		(property "Device Type" "SC1U10V2KX-4-GP_SMD-BCG6-SC1U1A"
			(at -1.1811 -4.3434 270)
			(unlocked yes)
			(layer "B.Fab")
			(hide yes)
			(effects
				(font
					(size 1.27 1.016)
					(thickness 0.1524)
				)
				(justify mirror)
			)
		)
		(duplicate_pad_numbers_are_jumpers no)
		(fp_rect
			(start 0.4318 0.9525)
			(end -0.4318 -0.9525)
			(stroke
				(width 0)
				(type default)
			)
			(fill no)
			(layer "B.CrtYd")
		)
		(fp_rect
			(start 0.4318 0.9525)
			(end -0.4318 -0.9525)
			(stroke
				(width 0)
				(type default)
			)
			(fill no)
			(layer "B.Fab")
		)
		(pad "1" smd custom
			(at 0 -0.4445 90)
			(size 0.1524 0.1524)
			(layers "B.Cu" "B.Mask" "B.Paste")
			(net "P5V_STBY")
			(options
				(clearance outline)
				(anchor circle)
			)
			(primitives
				(gr_poly
					(pts
						(arc
							(start 0.3048 0.2032)
							(mid 0.275042 0.275042)
							(end 0.2032 0.3048)
						)
						(arc
							(start -0.2032 0.3048)
							(mid -0.275042 0.275042)
							(end -0.3048 0.2032)
						)
						(arc
							(start -0.3048 -0.2032)
							(mid -0.275042 -0.275042)
							(end -0.2032 -0.3048)
						)
						(arc
							(start 0.2032 -0.3048)
							(mid 0.275042 -0.275042)
							(end 0.3048 -0.2032)
						)
					)
					(width 0)
					(fill yes)
				)
			)
		)
		(pad "2" smd custom
			(at 0 0.4445 90)
			(size 0.1524 0.1524)
			(layers "B.Cu" "B.Mask" "B.Paste")
			(net "GND")
			(options
				(clearance outline)
				(anchor circle)
			)
			(primitives
				(gr_poly
					(pts
						(arc
							(start 0.3048 0.2032)
							(mid 0.275042 0.275042)
							(end 0.2032 0.3048)
						)
						(arc
							(start -0.2032 0.3048)
							(mid -0.275042 0.275042)
							(end -0.3048 0.2032)
						)
						(arc
							(start -0.3048 -0.2032)
							(mid -0.275042 -0.275042)
							(end -0.2032 -0.3048)
						)
						(arc
							(start 0.2032 -0.3048)
							(mid 0.275042 -0.275042)
							(end 0.3048 -0.2032)
						)
					)
					(width 0)
					(fill yes)
				)
			)
		)
	)
	(footprint ""
		(layer "B.Cu")
		(at 104.5591 -12.954 90)
		(property "Reference" "C5G94"
			(at -1.14681 0.76708 180)
			(unlocked yes)
			(layer "B.SilkS")
			(effects
				(font
					(size 0.7874 0.5842)
					(thickness 0.1524)
				)
				(justify mirror)
			)
		)
		(property "Value" ""
			(at 0 0 90)
			(layer "B.Fab")
			(effects
				(font
					(size 1.27 1.27)
				)
				(justify mirror)
			)
		)
		(duplicate_pad_numbers_are_jumpers no)
		(fp_rect
			(start -0.4953 -0.2032)
			(end 0.4953 1.6002)
			(stroke
				(width 0)
				(type default)
			)
			(fill no)
			(layer "B.CrtYd")
		)
		(fp_line
			(start 0.4953 -0.2032)
			(end -0.4953 -0.2032)
			(stroke
				(width 0.1)
				(type default)
			)
			(layer "B.Fab")
		)
		(fp_line
			(start -0.4953 -0.2032)
			(end -0.4953 1.6002)
			(stroke
				(width 0.1)
				(type default)
			)
			(layer "B.Fab")
		)
		(fp_line
			(start 0.4953 1.6002)
			(end 0.4953 -0.2032)
			(stroke
				(width 0.1)
				(type default)
			)
			(layer "B.Fab")
		)
		(fp_line
			(start -0.4953 1.6002)
			(end 0.4953 1.6002)
			(stroke
				(width 0.1)
				(type default)
			)
			(layer "B.Fab")
		)
		(pad "1" smd rect
			(at 0 0 270)
			(size 0.762 0.889)
			(layers "B.Cu" "B.Mask" "B.Paste")
			(net "PVDDQ_GHJ")
		)
		(pad "2" smd rect
			(at 0 1.397 270)
			(size 0.762 0.889)
			(layers "B.Cu" "B.Mask" "B.Paste")
			(net "GND")
		)
		(zone
			(layer "B.Cu")
			(hatch none 0.5)
			(connect_pads
				(clearance 0)
			)
			(min_thickness 0.25)
			(keepout
				(tracks not_allowed)
				(vias allowed)
				(pads allowed)
				(copperpour not_allowed)
				(footprints allowed)
			)
			(placement
				(enabled no)
				(sheetname "")
			)
			(fill
				(thermal_gap 0.5)
				(thermal_bridge_width 0.5)
				(island_removal_mode 0)
			)
			(polygon
				(pts
					(xy 105.0036 -12.573) (xy 105.5116 -12.573) (xy 105.5116 -13.335) (xy 105.0036 -13.335)
				)
			)
		)
	)
)
